(kicad_pcb
	(version 20260206)
	(generator "pcbnew")
	(generator_version "10.0")
	(general
		(thickness 1.6)
		(legacy_teardrops no)
	)
	(paper "A4")
	(title_block
		(title "baseboard — 13948-1b.1110WZS1818.brd")
		(comment 1 "Honey Badger (Wiwynn) / footprints 2072-2079 of 2523")
	)
	(layers
		(0 "F.Cu" signal "TOP")
		(4 "In1.Cu" signal "L2GND")
		(6 "In2.Cu" signal "L3")
		(8 "In3.Cu" signal "L4VCC")
		(10 "In4.Cu" signal "L5VCC")
		(12 "In5.Cu" signal "L6")
		(14 "In6.Cu" signal "L7GND")
		(2 "B.Cu" signal "BOTTOM")
		(9 "F.Adhes" user "F.Adhesive")
		(11 "B.Adhes" user "B.Adhesive")
		(13 "F.Paste" user "Package Geometry/Pastemask Top")
		(15 "B.Paste" user "Package Geometry/Pastemask Bottom")
		(5 "F.SilkS" user "Ref Des/Silkscreen Top")
		(7 "B.SilkS" user "Ref Des/Silkscreen Bottom")
		(1 "F.Mask" user "Board Geometry/Soldermask Top")
		(3 "B.Mask" user "Board Geometry/Soldermask Bottom")
		(17 "Dwgs.User" user "User.Drawings")
		(19 "Cmts.User" user "User.Comments")
		(21 "Eco1.User" user "User.Eco1")
		(23 "Eco2.User" user "User.Eco2")
		(25 "Edge.Cuts" user "Board Geometry/Outline")
		(27 "Margin" user)
		(31 "F.CrtYd" user "Package Geometry/Place Bound Top")
		(29 "B.CrtYd" user "Package Geometry/Place Bound Bottom")
		(35 "F.Fab" user "Ref Des/Assembly Top")
		(33 "B.Fab" user "Ref Des/Assembly Bottom")
	)
	(footprint ""
		(layer "B.Cu")
		(at 122.44197 -94.996)
		(property "Reference" "SC1190"
			(at 0 0 0)
			(layer "B.SilkS")
			(hide yes)
			(effects
				(font
					(size 1.27 1.27)
				)
				(justify mirror)
			)
		)
		(property "Value" "SC1U6D3V1MX-GP"
			(at -1.9177 2.0193 0)
			(unlocked yes)
			(layer "B.Fab")
			(hide yes)
			(effects
				(font
					(size 1.016 1.016)
					(thickness 0.1524)
				)
				(justify mirror)
			)
		)
		(property "Device Type" "C0201H14"
			(at -1.9177 0.4953 0)
			(unlocked yes)
			(layer "B.Fab")
			(hide yes)
			(effects
				(font
					(size 1.016 1.016)
					(thickness 0.1524)
				)
				(justify mirror)
			)
		)
		(duplicate_pad_numbers_are_jumpers no)
		(fp_rect
			(start 0.1524 0.3048)
			(end -0.1524 -0.3048)
			(stroke
				(width 0)
				(type default)
			)
			(fill no)
			(layer "B.CrtYd")
		)
		(fp_poly
			(pts
				(xy 0.2794 0.6477) (xy 0.2794 -0.6477) (xy -0.2794 -0.6477) (xy -0.2794 -0.1905) (xy -0.1524 -0.1905)
				(xy -0.1524 -0.3048) (xy 0.1524 -0.3048) (xy 0.1524 0.3048) (xy -0.1524 0.3048) (xy -0.1524 -0.1778)
				(xy -0.2794 -0.1778) (xy -0.2794 0.6477)
			)
			(stroke
				(width 0)
				(type default)
			)
			(fill no)
			(layer "B.CrtYd")
		)
		(fp_rect
			(start 0.2794 0.6477)
			(end -0.2794 -0.6477)
			(stroke
				(width 0)
				(type default)
			)
			(fill no)
			(layer "B.Fab")
		)
		(pad "1" smd custom
			(at 0 -0.2794 180)
			(size 0.0762 0.0762)
			(layers "B.Cu" "B.Mask" "B.Paste")
			(net "GB_VDDA")
			(options
				(clearance outline)
				(anchor circle)
			)
			(primitives
				(gr_poly
					(pts
						(arc
							(start 0.1524 0.127)
							(mid 0.137521 0.162921)
							(end 0.1016 0.1778)
						)
						(arc
							(start -0.1016 0.1778)
							(mid -0.137521 0.162921)
							(end -0.1524 0.127)
						)
						(arc
							(start -0.1524 -0.127)
							(mid -0.137521 -0.162921)
							(end -0.1016 -0.1778)
						)
						(arc
							(start 0.1016 -0.1778)
							(mid 0.137521 -0.162921)
							(end 0.1524 -0.127)
						)
					)
					(width 0)
					(fill yes)
				)
			)
		)
		(pad "2" smd custom
			(at 0 0.2794 180)
			(size 0.0762 0.0762)
			(layers "B.Cu" "B.Mask" "B.Paste")
			(net "GND")
			(options
				(clearance outline)
				(anchor circle)
			)
			(primitives
				(gr_poly
					(pts
						(arc
							(start 0.1524 0.127)
							(mid 0.137521 0.162921)
							(end 0.1016 0.1778)
						)
						(arc
							(start -0.1016 0.1778)
							(mid -0.137521 0.162921)
							(end -0.1524 0.127)
						)
						(arc
							(start -0.1524 -0.127)
							(mid -0.137521 -0.162921)
							(end -0.1016 -0.1778)
						)
						(arc
							(start 0.1016 -0.1778)
							(mid 0.137521 -0.162921)
							(end 0.1524 -0.127)
						)
					)
					(width 0)
					(fill yes)
				)
			)
		)
	)
	(footprint ""
		(layer "B.Cu")
		(at 88.91397 -136.779 90)
		(property "Reference" "SC1118"
			(at 0 0 90)
			(layer "B.SilkS")
			(hide yes)
			(effects
				(font
					(size 1.27 1.27)
				)
				(justify mirror)
			)
		)
		(property "Value" "SCD1U16V2KX-3GP"
			(at -1.1811 -2.7051 90)
			(unlocked yes)
			(layer "B.Fab")
			(hide yes)
			(effects
				(font
					(size 1.016 1.016)
					(thickness 0.1524)
				)
				(justify mirror)
			)
		)
		(property "Device Type" "C402H22"
			(at -1.1811 -4.2291 90)
			(unlocked yes)
			(layer "B.Fab")
			(hide yes)
			(effects
				(font
					(size 1.016 1.016)
					(thickness 0.1524)
				)
				(justify mirror)
			)
		)
		(duplicate_pad_numbers_are_jumpers no)
		(fp_rect
			(start 0.4318 0.9525)
			(end -0.4318 -0.9525)
			(stroke
				(width 0)
				(type default)
			)
			(fill no)
			(layer "B.CrtYd")
		)
		(fp_rect
			(start 0.4318 0.9525)
			(end -0.4318 -0.9525)
			(stroke
				(width 0)
				(type default)
			)
			(fill no)
			(layer "B.Fab")
		)
		(pad "1" smd custom
			(at 0 -0.4445 270)
			(size 0.1524 0.1524)
			(layers "B.Cu" "B.Mask" "B.Paste")
			(net "P3V3_STBY")
			(options
				(clearance outline)
				(anchor circle)
			)
			(primitives
				(gr_poly
					(pts
						(arc
							(start 0.3048 0.2032)
							(mid 0.275042 0.275042)
							(end 0.2032 0.3048)
						)
						(arc
							(start -0.2032 0.3048)
							(mid -0.275042 0.275042)
							(end -0.3048 0.2032)
						)
						(arc
							(start -0.3048 -0.2032)
							(mid -0.275042 -0.275042)
							(end -0.2032 -0.3048)
						)
						(arc
							(start 0.2032 -0.3048)
							(mid 0.275042 -0.275042)
							(end 0.3048 -0.2032)
						)
					)
					(width 0)
					(fill yes)
				)
			)
		)
		(pad "2" smd custom
			(at 0 0.4445 270)
			(size 0.1524 0.1524)
			(layers "B.Cu" "B.Mask" "B.Paste")
			(net "GND")
			(options
				(clearance outline)
				(anchor circle)
			)
			(primitives
				(gr_poly
					(pts
						(arc
							(start 0.3048 0.2032)
							(mid 0.275042 0.275042)
							(end 0.2032 0.3048)
						)
						(arc
							(start -0.2032 0.3048)
							(mid -0.275042 0.275042)
							(end -0.3048 0.2032)
						)
						(arc
							(start -0.3048 -0.2032)
							(mid -0.275042 -0.275042)
							(end -0.2032 -0.3048)
						)
						(arc
							(start 0.2032 -0.3048)
							(mid 0.275042 -0.275042)
							(end 0.3048 -0.2032)
						)
					)
					(width 0)
					(fill yes)
				)
			)
		)
	)
	(footprint ""
		(layer "B.Cu")
		(at 185.474864 -33.981136)
		(property "Reference" "C221"
			(at 0 0 0)
			(layer "B.SilkS")
			(hide yes)
			(effects
				(font
					(size 1.27 1.27)
				)
				(justify mirror)
			)
		)
		(property "Value" "SC1KP50V2KX-1GP"
			(at -1.1811 -2.7051 0)
			(unlocked yes)
			(layer "B.Fab")
			(hide yes)
			(effects
				(font
					(size 1.016 1.016)
					(thickness 0.1524)
				)
				(justify mirror)
			)
		)
		(property "Device Type" "C402H22"
			(at -1.1811 -4.2291 0)
			(unlocked yes)
			(layer "B.Fab")
			(hide yes)
			(effects
				(font
					(size 1.016 1.016)
					(thickness 0.1524)
				)
				(justify mirror)
			)
		)
		(duplicate_pad_numbers_are_jumpers no)
		(fp_rect
			(start 0.4318 0.9525)
			(end -0.4318 -0.9525)
			(stroke
				(width 0)
				(type default)
			)
			(fill no)
			(layer "B.CrtYd")
		)
		(fp_rect
			(start 0.4318 0.9525)
			(end -0.4318 -0.9525)
			(stroke
				(width 0)
				(type default)
			)
			(fill no)
			(layer "B.Fab")
		)
		(pad "1" smd custom
			(at 0 -0.4445 180)
			(size 0.1524 0.1524)
			(layers "B.Cu" "B.Mask" "B.Paste")
			(net "P3V3_STBY")
			(options
				(clearance outline)
				(anchor circle)
			)
			(primitives
				(gr_poly
					(pts
						(arc
							(start 0.3048 0.2032)
							(mid 0.275042 0.275042)
							(end 0.2032 0.3048)
						)
						(arc
							(start -0.2032 0.3048)
							(mid -0.275042 0.275042)
							(end -0.3048 0.2032)
						)
						(arc
							(start -0.3048 -0.2032)
							(mid -0.275042 -0.275042)
							(end -0.2032 -0.3048)
						)
						(arc
							(start 0.2032 -0.3048)
							(mid 0.275042 -0.275042)
							(end 0.3048 -0.2032)
						)
					)
					(width 0)
					(fill yes)
				)
			)
		)
		(pad "2" smd custom
			(at 0 0.4445 180)
			(size 0.1524 0.1524)
			(layers "B.Cu" "B.Mask" "B.Paste")
			(net "GND")
			(options
				(clearance outline)
				(anchor circle)
			)
			(primitives
				(gr_poly
					(pts
						(arc
							(start 0.3048 0.2032)
							(mid 0.275042 0.275042)
							(end 0.2032 0.3048)
						)
						(arc
							(start -0.2032 0.3048)
							(mid -0.275042 0.275042)
							(end -0.3048 0.2032)
						)
						(arc
							(start -0.3048 -0.2032)
							(mid -0.275042 -0.275042)
							(end -0.2032 -0.3048)
						)
						(arc
							(start 0.2032 -0.3048)
							(mid 0.275042 -0.275042)
							(end 0.3048 -0.2032)
						)
					)
					(width 0)
					(fill yes)
				)
			)
		)
	)
	(footprint ""
		(layer "B.Cu")
		(at 264.541 -16.891 180)
		(property "Reference" "C336"
			(at 0 0 0)
			(layer "B.SilkS")
			(hide yes)
			(effects
				(font
					(size 1.27 1.27)
				)
				(justify mirror)
			)
		)
		(property "Value" "SC1U10V3KX-4GP-U"
			(at 0 -2.8194 180)
			(unlocked yes)
			(layer "B.Fab")
			(hide yes)
			(effects
				(font
					(size 1.016 1.016)
					(thickness 0.1524)
				)
				(justify mirror)
			)
		)
		(property "Device Type" "C603H36"
			(at 0 -4.3434 180)
			(unlocked yes)
			(layer "B.Fab")
			(hide yes)
			(effects
				(font
					(size 1.016 1.016)
					(thickness 0.1524)
				)
				(justify mirror)
			)
		)
		(duplicate_pad_numbers_are_jumpers no)
		(fp_line
			(start -0.508 0)
			(end 0.508 0)
			(stroke
				(width 0.2032)
				(type default)
			)
			(layer "B.SilkS")
		)
		(fp_rect
			(start 0.5842 1.3335)
			(end -0.5842 -1.3335)
			(stroke
				(width 0)
				(type default)
			)
			(fill no)
			(layer "B.CrtYd")
		)
		(fp_rect
			(start 0.5842 1.3335)
			(end -0.5842 -1.3335)
			(stroke
				(width 0)
				(type default)
			)
			(fill no)
			(layer "B.Fab")
		)
		(pad "1" smd custom
			(at 0 -0.762)
			(size 0.2159 0.2159)
			(layers "B.Cu" "B.Mask" "B.Paste")
			(net "P5V_USB")
			(options
				(clearance outline)
				(anchor circle)
			)
			(primitives
				(gr_poly
					(pts
						(arc
							(start -0.3302 0.4318)
							(mid -0.402042 0.402042)
							(end -0.4318 0.3302)
						)
						(arc
							(start -0.4318 -0.3302)
							(mid -0.402042 -0.402042)
							(end -0.3302 -0.4318)
						)
						(arc
							(start 0.3302 -0.4318)
							(mid 0.402042 -0.402042)
							(end 0.4318 -0.3302)
						)
						(arc
							(start 0.4318 0.3302)
							(mid 0.402042 0.402042)
							(end 0.3302 0.4318)
						)
					)
					(width 0)
					(fill yes)
				)
			)
		)
		(pad "2" smd custom
			(at 0 0.762)
			(size 0.2159 0.2159)
			(layers "B.Cu" "B.Mask" "B.Paste")
			(net "GND")
			(options
				(clearance outline)
				(anchor circle)
			)
			(primitives
				(gr_poly
					(pts
						(arc
							(start -0.3302 0.4318)
							(mid -0.402042 0.402042)
							(end -0.4318 0.3302)
						)
						(arc
							(start -0.4318 -0.3302)
							(mid -0.402042 -0.402042)
							(end -0.3302 -0.4318)
						)
						(arc
							(start 0.3302 -0.4318)
							(mid 0.402042 -0.402042)
							(end 0.4318 -0.3302)
						)
						(arc
							(start 0.4318 0.3302)
							(mid 0.402042 0.402042)
							(end 0.3302 0.4318)
						)
					)
					(width 0)
					(fill yes)
				)
			)
		)
	)
	(footprint ""
		(layer "B.Cu")
		(at 158.42996 -110.591854 90)
		(property "Reference" "SC1246"
			(at 0 0 90)
			(layer "B.SilkS")
			(hide yes)
			(effects
				(font
					(size 1.27 1.27)
				)
				(justify mirror)
			)
		)
		(property "Value" "SCD1U6D3V1KX-GP"
			(at 2.8321 -1.7399 90)
			(unlocked yes)
			(layer "B.Fab")
			(hide yes)
			(effects
				(font
					(size 1.016 1.016)
					(thickness 0.1524)
				)
				(justify mirror)
			)
		)
		(property "Device Type" "C0201H13"
			(at 2.8321 -3.2639 90)
			(unlocked yes)
			(layer "B.Fab")
			(hide yes)
			(effects
				(font
					(size 1.016 1.016)
					(thickness 0.1524)
				)
				(justify mirror)
			)
		)
		(duplicate_pad_numbers_are_jumpers no)
		(fp_rect
			(start 0.2794 0.6477)
			(end -0.2794 -0.6477)
			(stroke
				(width 0)
				(type default)
			)
			(fill no)
			(layer "B.CrtYd")
		)
		(fp_rect
			(start 0.2794 0.6477)
			(end -0.2794 -0.6477)
			(stroke
				(width 0)
				(type default)
			)
			(fill no)
			(layer "B.Fab")
		)
		(pad "1" smd custom
			(at 0 -0.2794 270)
			(size 0.0762 0.0762)
			(layers "B.Cu" "B.Mask" "B.Paste")
			(net "P0V9_E")
			(options
				(clearance outline)
				(anchor circle)
			)
			(primitives
				(gr_poly
					(pts
						(arc
							(start 0.1524 0.127)
							(mid 0.137521 0.162921)
							(end 0.1016 0.1778)
						)
						(arc
							(start -0.1016 0.1778)
							(mid -0.137521 0.162921)
							(end -0.1524 0.127)
						)
						(arc
							(start -0.1524 -0.127)
							(mid -0.137521 -0.162921)
							(end -0.1016 -0.1778)
						)
						(arc
							(start 0.1016 -0.1778)
							(mid 0.137521 -0.162921)
							(end 0.1524 -0.127)
						)
					)
					(width 0)
					(fill yes)
				)
			)
		)
		(pad "2" smd custom
			(at 0 0.2794 270)
			(size 0.0762 0.0762)
			(layers "B.Cu" "B.Mask" "B.Paste")
			(net "GND")
			(options
				(clearance outline)
				(anchor circle)
			)
			(primitives
				(gr_poly
					(pts
						(arc
							(start 0.1524 0.127)
							(mid 0.137521 0.162921)
							(end 0.1016 0.1778)
						)
						(arc
							(start -0.1016 0.1778)
							(mid -0.137521 0.162921)
							(end -0.1524 0.127)
						)
						(arc
							(start -0.1524 -0.127)
							(mid -0.137521 -0.162921)
							(end -0.1016 -0.1778)
						)
						(arc
							(start 0.1016 -0.1778)
							(mid 0.137521 -0.162921)
							(end 0.1524 -0.127)
						)
					)
					(width 0)
					(fill yes)
				)
			)
		)
	)
	(footprint ""
		(layer "B.Cu")
		(at 292.354 -179.07)
		(property "Reference" "C204"
			(at 0 0 0)
			(layer "B.SilkS")
			(hide yes)
			(effects
				(font
					(size 1.27 1.27)
				)
				(justify mirror)
			)
		)
		(property "Value" "SC1U10V3KX-4GP-U"
			(at 0 -2.8194 0)
			(unlocked yes)
			(layer "B.Fab")
			(hide yes)
			(effects
				(font
					(size 1.016 1.016)
					(thickness 0.1524)
				)
				(justify mirror)
			)
		)
		(property "Device Type" "C603H36"
			(at 0 -4.3434 0)
			(unlocked yes)
			(layer "B.Fab")
			(hide yes)
			(effects
				(font
					(size 1.016 1.016)
					(thickness 0.1524)
				)
				(justify mirror)
			)
		)
		(duplicate_pad_numbers_are_jumpers no)
		(fp_line
			(start -0.508 0)
			(end 0.508 0)
			(stroke
				(width 0.2032)
				(type default)
			)
			(layer "B.SilkS")
		)
		(fp_rect
			(start 0.5842 1.3335)
			(end -0.5842 -1.3335)
			(stroke
				(width 0)
				(type default)
			)
			(fill no)
			(layer "B.CrtYd")
		)
		(fp_rect
			(start 0.5842 1.3335)
			(end -0.5842 -1.3335)
			(stroke
				(width 0)
				(type default)
			)
			(fill no)
			(layer "B.Fab")
		)
		(pad "1" smd custom
			(at 0 -0.762 180)
			(size 0.2159 0.2159)
			(layers "B.Cu" "B.Mask" "B.Paste")
			(net "P1V26_STBY")
			(options
				(clearance outline)
				(anchor circle)
			)
			(primitives
				(gr_poly
					(pts
						(arc
							(start -0.3302 0.4318)
							(mid -0.402042 0.402042)
							(end -0.4318 0.3302)
						)
						(arc
							(start -0.4318 -0.3302)
							(mid -0.402042 -0.402042)
							(end -0.3302 -0.4318)
						)
						(arc
							(start 0.3302 -0.4318)
							(mid 0.402042 -0.402042)
							(end 0.4318 -0.3302)
						)
						(arc
							(start 0.4318 0.3302)
							(mid 0.402042 0.402042)
							(end 0.3302 0.4318)
						)
					)
					(width 0)
					(fill yes)
				)
			)
		)
		(pad "2" smd custom
			(at 0 0.762 180)
			(size 0.2159 0.2159)
			(layers "B.Cu" "B.Mask" "B.Paste")
			(net "GND")
			(options
				(clearance outline)
				(anchor circle)
			)
			(primitives
				(gr_poly
					(pts
						(arc
							(start -0.3302 0.4318)
							(mid -0.402042 0.402042)
							(end -0.4318 0.3302)
						)
						(arc
							(start -0.4318 -0.3302)
							(mid -0.402042 -0.402042)
							(end -0.3302 -0.4318)
						)
						(arc
							(start 0.3302 -0.4318)
							(mid 0.402042 -0.402042)
							(end 0.4318 -0.3302)
						)
						(arc
							(start 0.4318 0.3302)
							(mid 0.402042 0.402042)
							(end 0.3302 0.4318)
						)
					)
					(width 0)
					(fill yes)
				)
			)
		)
	)
	(footprint ""
		(layer "B.Cu")
		(at 109.544612 -222.885 180)
		(property "Reference" "SR898"
			(at 0 0 0)
			(layer "B.SilkS")
			(hide yes)
			(effects
				(font
					(size 1.27 1.27)
				)
				(justify mirror)
			)
		)
		(property "Value" "0R2J-2-GP"
			(at -0.064008 -3.993896 180)
			(unlocked yes)
			(layer "B.Fab")
			(hide yes)
			(effects
				(font
					(size 1.016 1.016)
					(thickness 0.1524)
				)
				(justify mirror)
			)
		)
		(property "Device Type" "R402H16"
			(at -0.064008 -5.517896 180)
			(unlocked yes)
			(layer "B.Fab")
			(hide yes)
			(effects
				(font
					(size 1.016 1.016)
					(thickness 0.1524)
				)
				(justify mirror)
			)
		)
		(duplicate_pad_numbers_are_jumpers no)
		(fp_line
			(start 0.508 -0.9398)
			(end 0.508 0.9398)
			(stroke
				(width 0.1524)
				(type default)
			)
			(layer "B.SilkS")
		)
		(fp_line
			(start -0.508 -0.9398)
			(end 0.508 -0.9398)
			(stroke
				(width 0.1524)
				(type default)
			)
			(layer "B.SilkS")
		)
		(fp_rect
			(start 0.508 0.9398)
			(end -0.508 -0.9398)
			(stroke
				(width 0)
				(type default)
			)
			(fill no)
			(layer "B.CrtYd")
		)
		(fp_rect
			(start 0.508 0.9398)
			(end -0.508 -0.9398)
			(stroke
				(width 0)
				(type default)
			)
			(fill no)
			(layer "B.Fab")
		)
		(pad "1" smd custom
			(at 0 -0.4445)
			(size 0.1397 0.1397)
			(layers "B.Cu" "B.Mask" "B.Paste")
			(net "SAS_GF_EXP_RX_DN8")
			(options
				(clearance outline)
				(anchor circle)
			)
			(primitives
				(gr_poly
					(pts
						(arc
							(start -0.1778 0.2794)
							(mid -0.249642 0.249642)
							(end -0.2794 0.1778)
						)
						(arc
							(start -0.2794 -0.1778)
							(mid -0.249642 -0.249642)
							(end -0.1778 -0.2794)
						)
						(arc
							(start 0.1778 -0.2794)
							(mid 0.249642 -0.249642)
							(end 0.2794 -0.1778)
						)
						(arc
							(start 0.2794 0.1778)
							(mid 0.249642 0.249642)
							(end 0.1778 0.2794)
						)
					)
					(width 0)
					(fill yes)
				)
			)
		)
		(pad "2" smd custom
			(at 0 0.4445)
			(size 0.1397 0.1397)
			(layers "B.Cu" "B.Mask" "B.Paste")
			(net "REDV_RX8_N")
			(options
				(clearance outline)
				(anchor circle)
			)
			(primitives
				(gr_poly
					(pts
						(arc
							(start -0.1778 0.2794)
							(mid -0.249642 0.249642)
							(end -0.2794 0.1778)
						)
						(arc
							(start -0.2794 -0.1778)
							(mid -0.249642 -0.249642)
							(end -0.1778 -0.2794)
						)
						(arc
							(start 0.1778 -0.2794)
							(mid 0.249642 -0.249642)
							(end 0.2794 -0.1778)
						)
						(arc
							(start 0.2794 0.1778)
							(mid 0.249642 0.249642)
							(end 0.1778 0.2794)
						)
					)
					(width 0)
					(fill yes)
				)
			)
		)
	)
	(footprint ""
		(layer "B.Cu")
		(at 112.293146 -47.6504)
		(property "Reference" "STP15"
			(at 0 0 0)
			(layer "B.SilkS")
			(hide yes)
			(effects
				(font
					(size 1.27 1.27)
				)
				(justify mirror)
			)
		)
		(property "Value" "TPAD28"
			(at -0.0127 -1.8034 0)
			(unlocked yes)
			(layer "B.Fab")
			(hide yes)
			(effects
				(font
					(size 1.016 1.016)
					(thickness 0.1524)
				)
				(justify mirror)
			)
		)
		(property "Device Type" "TPAD28"
			(at -0.0127 -3.3274 0)
			(unlocked yes)
			(layer "B.Fab")
			(hide yes)
			(effects
				(font
					(size 1.016 1.016)
					(thickness 0.1524)
				)
				(justify mirror)
			)
		)
		(duplicate_pad_numbers_are_jumpers no)
		(fp_poly
			(pts
				(arc
					(start 0.3556 0)
					(mid -0.3556 0)
					(end 0.3556 0)
				)
			)
			(stroke
				(width 0)
				(type default)
			)
			(fill no)
			(layer "B.CrtYd")
		)
		(fp_poly
			(pts
				(arc
					(start 0.6096 0)
					(mid -0.6096 0)
					(end 0.6096 0)
				)
			)
			(stroke
				(width 0)
				(type default)
			)
			(fill no)
			(layer "B.Fab")
		)
		(pad "1" smd circle
			(at 0 0 180)
			(size 0.7112 0.7112)
			(layers "B.Cu" "B.Mask" "B.Paste")
			(net "IOC_GPIO_32")
		)
	)
)
